# T6G (Grand Teton) — schematic netlist excerpt (pin names and nets, part order shuffled) for the footprints in the layout excerpt that follows; sources: Cadence DE-HDL packaged netlist, KiCad conversion of 04192023_DAF0TMB3IC0_F0TG_MB_C_brd_V02_OCP.brd

C5005  Q_CAP  1000PF 50V 5% X7R  pkg 0402  page 200 : A = GND ; B = PWRGD_PVDDIO_P0
C974  Q_CAP  22UF 4V 20% X6S  pkg C0402  page 301 : A = P0V9_CPU0_RT2_2A ; B = GND

(kicad_pcb
	(version 20260206)
	(generator "pcbnew")
	(generator_version "10.0")
	(general
		(thickness 1.6)
		(legacy_teardrops no)
	)
	(paper "A4")
	(title_block
		(title "04192023_DAF0TMB3IC0_F0TG_MB_C_brd_V02_OCP.brd")
		(comment 1 "Grand Teton / footprints 7837-7838 of 8354")
	)
	(layers
		(0 "F.Cu" signal "TOP")
		(4 "In1.Cu" signal "GND")
		(6 "In2.Cu" signal "IN1")
		(8 "In3.Cu" signal "GND1")
		(10 "In4.Cu" signal "IN2")
		(12 "In5.Cu" signal "GND2")
		(14 "In6.Cu" signal "IN3")
		(16 "In7.Cu" signal "GND3")
		(18 "In8.Cu" signal "VCC")
		(20 "In9.Cu" signal "VCC1")
		(22 "In10.Cu" signal "GND4")
		(24 "In11.Cu" signal "IN4")
		(26 "In12.Cu" signal "GND5")
		(28 "In13.Cu" signal "IN5")
		(30 "In14.Cu" signal "GND6")
		(32 "In15.Cu" signal "IN6")
		(34 "In16.Cu" signal "GND7")
		(2 "B.Cu" signal "BOTTOM")
		(9 "F.Adhes" user "F.Adhesive")
		(11 "B.Adhes" user "B.Adhesive")
		(13 "F.Paste" user "Package Geometry/Pastemask Top")
		(15 "B.Paste" user "Package Geometry/Pastemask Bottom")
		(5 "F.SilkS" user "Ref Des/Silkscreen Top")
		(7 "B.SilkS" user "Ref Des/Silkscreen Bottom")
		(1 "F.Mask" user "Board Geometry/Soldermask Top")
		(3 "B.Mask" user "Board Geometry/Soldermask Bottom")
		(17 "Dwgs.User" user "User.Drawings")
		(19 "Cmts.User" user "User.Comments")
		(21 "Eco1.User" user "User.Eco1")
		(23 "Eco2.User" user "User.Eco2")
		(25 "Edge.Cuts" user "Board Geometry/Outline")
		(27 "Margin" user)
		(31 "F.CrtYd" user "Package Geometry/Place Bound Top")
		(29 "B.CrtYd" user "Package Geometry/Place Bound Bottom")
		(35 "F.Fab" user "Ref Des/Assembly Top")
		(33 "B.Fab" user "Ref Des/Assembly Bottom")
	)
	(footprint ""
		(layer "B.Cu")
		(at 404.218902 -398.942052 90)
		(property "Reference" "C974"
			(at 0 0 90)
			(layer "B.SilkS")
			(hide yes)
			(effects
				(font
					(size 1.27 1.27)
				)
				(justify mirror)
			)
		)
		(property "Value" ""
			(at 0 0 90)
			(layer "B.Fab")
			(effects
				(font
					(size 1.27 1.27)
				)
				(justify mirror)
			)
		)
		(duplicate_pad_numbers_are_jumpers no)
		(fp_line
			(start 0.7874 -0.4064)
			(end -0.7874 -0.4064)
			(stroke
				(width 0.1524)
				(type default)
			)
			(layer "B.SilkS")
		)
		(fp_line
			(start -0.7874 -0.4064)
			(end -0.7874 0.4064)
			(stroke
				(width 0.1524)
				(type default)
			)
			(layer "B.SilkS")
		)
		(fp_line
			(start 0.7874 0.4064)
			(end 0.7874 -0.4064)
			(stroke
				(width 0.1524)
				(type default)
			)
			(layer "B.SilkS")
		)
		(fp_line
			(start -0.7874 0.4064)
			(end 0.7874 0.4064)
			(stroke
				(width 0.1524)
				(type default)
			)
			(layer "B.SilkS")
		)
		(fp_line
			(start 0.67945 -0.305054)
			(end 0.12065 -0.305054)
			(stroke
				(width 0.1)
				(type default)
			)
			(layer "B.Fab")
		)
		(fp_line
			(start 0.12065 -0.305054)
			(end 0.12065 -0.2794)
			(stroke
				(width 0.1)
				(type default)
			)
			(layer "B.Fab")
		)
		(fp_line
			(start -0.12065 -0.3048)
			(end -0.67945 -0.3048)
			(stroke
				(width 0.1)
				(type default)
			)
			(layer "B.Fab")
		)
		(fp_line
			(start -0.67945 -0.3048)
			(end -0.67945 0.3048)
			(stroke
				(width 0.1)
				(type default)
			)
			(layer "B.Fab")
		)
		(fp_line
			(start 0.12065 -0.2794)
			(end -0.12065 -0.2794)
			(stroke
				(width 0.1)
				(type default)
			)
			(layer "B.Fab")
		)
		(fp_line
			(start -0.12065 -0.2794)
			(end -0.12065 -0.3048)
			(stroke
				(width 0.1)
				(type default)
			)
			(layer "B.Fab")
		)
		(fp_line
			(start 0.12065 0.2794)
			(end 0.12065 0.3048)
			(stroke
				(width 0.1)
				(type default)
			)
			(layer "B.Fab")
		)
		(fp_line
			(start -0.120396 0.2794)
			(end 0.12065 0.2794)
			(stroke
				(width 0.1)
				(type default)
			)
			(layer "B.Fab")
		)
		(fp_line
			(start 0.67945 0.3048)
			(end 0.67945 -0.305054)
			(stroke
				(width 0.1)
				(type default)
			)
			(layer "B.Fab")
		)
		(fp_line
			(start 0.12065 0.3048)
			(end 0.67945 0.3048)
			(stroke
				(width 0.1)
				(type default)
			)
			(layer "B.Fab")
		)
		(fp_line
			(start -0.120396 0.3048)
			(end -0.120396 0.2794)
			(stroke
				(width 0.1)
				(type default)
			)
			(layer "B.Fab")
		)
		(fp_line
			(start -0.67945 0.3048)
			(end -0.120396 0.3048)
			(stroke
				(width 0.1)
				(type default)
			)
			(layer "B.Fab")
		)
		(pad "1" smd circle
			(at 0.40005 0 270)
			(size 0 0)
			(layers "B.Cu" "B.Mask" "B.Paste")
			(net "P0V9_CPU0_RT2_2A")
		)
		(pad "2" smd circle
			(at -0.40005 0 270)
			(size 0 0)
			(layers "B.Cu" "B.Mask" "B.Paste")
			(net "GND")
		)
	)
	(footprint ""
		(layer "B.Cu")
		(at 302.133 -359.283 180)
		(property "Reference" "C5005"
			(at 0 0 0)
			(layer "B.SilkS")
			(hide yes)
			(effects
				(font
					(size 1.27 1.27)
				)
				(justify mirror)
			)
		)
		(property "Value" ""
			(at 0 0 0)
			(layer "B.Fab")
			(effects
				(font
					(size 1.27 1.27)
				)
				(justify mirror)
			)
		)
		(duplicate_pad_numbers_are_jumpers no)
		(fp_line
			(start 0.7874 0.4064)
			(end 0.7874 -0.4064)
			(stroke
				(width 0.1524)
				(type default)
			)
			(layer "B.SilkS")
		)
		(fp_line
			(start 0.7874 -0.4064)
			(end -0.7874 -0.4064)
			(stroke
				(width 0.1524)
				(type default)
			)
			(layer "B.SilkS")
		)
		(fp_line
			(start -0.7874 0.4064)
			(end 0.7874 0.4064)
			(stroke
				(width 0.1524)
				(type default)
			)
			(layer "B.SilkS")
		)
		(fp_line
			(start -0.7874 -0.4064)
			(end -0.7874 0.4064)
			(stroke
				(width 0.1524)
				(type default)
			)
			(layer "B.SilkS")
		)
		(fp_line
			(start 0.67945 0.3048)
			(end 0.67945 -0.305054)
			(stroke
				(width 0.1)
				(type default)
			)
			(layer "B.Fab")
		)
		(fp_line
			(start 0.67945 -0.305054)
			(end 0.12065 -0.305054)
			(stroke
				(width 0.1)
				(type default)
			)
			(layer "B.Fab")
		)
		(fp_line
			(start 0.12065 0.3048)
			(end 0.67945 0.3048)
			(stroke
				(width 0.1)
				(type default)
			)
			(layer "B.Fab")
		)
		(fp_line
			(start 0.12065 0.2794)
			(end 0.12065 0.3048)
			(stroke
				(width 0.1)
				(type default)
			)
			(layer "B.Fab")
		)
		(fp_line
			(start 0.12065 -0.2794)
			(end -0.12065 -0.2794)
			(stroke
				(width 0.1)
				(type default)
			)
			(layer "B.Fab")
		)
		(fp_line
			(start 0.12065 -0.305054)
			(end 0.12065 -0.2794)
			(stroke
				(width 0.1)
				(type default)
			)
			(layer "B.Fab")
		)
		(fp_line
			(start -0.120396 0.3048)
			(end -0.120396 0.2794)
			(stroke
				(width 0.1)
				(type default)
			)
			(layer "B.Fab")
		)
		(fp_line
			(start -0.120396 0.2794)
			(end 0.12065 0.2794)
			(stroke
				(width 0.1)
				(type default)
			)
			(layer "B.Fab")
		)
		(fp_line
			(start -0.12065 -0.2794)
			(end -0.12065 -0.3048)
			(stroke
				(width 0.1)
				(type default)
			)
			(layer "B.Fab")
		)
		(fp_line
			(start -0.12065 -0.3048)
			(end -0.67945 -0.3048)
			(stroke
				(width 0.1)
				(type default)
			)
			(layer "B.Fab")
		)
		(fp_line
			(start -0.67945 0.3048)
			(end -0.120396 0.3048)
			(stroke
				(width 0.1)
				(type default)
			)
			(layer "B.Fab")
		)
		(fp_line
			(start -0.67945 -0.3048)
			(end -0.67945 0.3048)
			(stroke
				(width 0.1)
				(type default)
			)
			(layer "B.Fab")
		)
		(pad "1" smd circle
			(at 0.40005 0)
			(size 0 0)
			(layers "B.Cu" "B.Mask" "B.Paste")
			(net "GND")
		)
		(pad "2" smd circle
			(at -0.40005 0)
			(size 0 0)
			(layers "B.Cu" "B.Mask" "B.Paste")
			(net "PWRGD_PVDDIO_P0")
		)
	)
)
